(kicad_pcb
	(version 20260206)
	(generator "pcbnew")
	(generator_version "10.0")
	(general
		(thickness 1.6)
		(legacy_teardrops no)
	)
	(paper "A4")
	(title_block
		(title "Bryce Canyon_IOM_M2_16342-2_OCP.brd")
		(comment 1 "Bryce Canyon / footprints 28-31 of 1146")
	)
	(layers
		(0 "F.Cu" signal "TOP")
		(4 "In1.Cu" signal "L2GND")
		(6 "In2.Cu" signal "L3")
		(8 "In3.Cu" signal "L4VCC")
		(10 "In4.Cu" signal "L5VCC")
		(12 "In5.Cu" signal "L6")
		(14 "In6.Cu" signal "L7GND")
		(2 "B.Cu" signal "BOTTOM")
		(9 "F.Adhes" user "F.Adhesive")
		(11 "B.Adhes" user "B.Adhesive")
		(13 "F.Paste" user "Package Geometry/Pastemask Top")
		(15 "B.Paste" user "Package Geometry/Pastemask Bottom")
		(5 "F.SilkS" user "Ref Des/Silkscreen Top")
		(7 "B.SilkS" user "Ref Des/Silkscreen Bottom")
		(1 "F.Mask" user "Board Geometry/Soldermask Top")
		(3 "B.Mask" user "Board Geometry/Soldermask Bottom")
		(17 "Dwgs.User" user "User.Drawings")
		(19 "Cmts.User" user "User.Comments")
		(21 "Eco1.User" user "User.Eco1")
		(23 "Eco2.User" user "User.Eco2")
		(25 "Edge.Cuts" user "Board Geometry/Outline")
		(27 "Margin" user)
		(31 "F.CrtYd" user "Package Geometry/Place Bound Top")
		(29 "B.CrtYd" user "Package Geometry/Place Bound Bottom")
		(35 "F.Fab" user "Ref Des/Assembly Top")
		(33 "B.Fab" user "Ref Des/Assembly Bottom")
	)
	(footprint ""
		(layer "F.Cu")
		(at 149.28088 -12.81049 90)
		(property "Reference" "R513"
			(at 0 0 90)
			(layer "F.SilkS")
			(hide yes)
			(effects
				(font
					(size 1.27 1.27)
				)
			)
		)
		(property "Value" "10KR2F-2-GP"
			(at 0.064008 -3.993896 90)
			(unlocked yes)
			(layer "F.Fab")
			(hide yes)
			(effects
				(font
					(size 1.016 1.016)
					(thickness 0.1524)
				)
			)
		)
		(property "Device Type" "R402H16"
			(at 0.064008 -5.517896 90)
			(unlocked yes)
			(layer "F.Fab")
			(hide yes)
			(effects
				(font
					(size 1.016 1.016)
					(thickness 0.1524)
				)
			)
		)
		(duplicate_pad_numbers_are_jumpers no)
		(fp_line
			(start 0.508 -0.9398)
			(end -0.508 -0.9398)
			(stroke
				(width 0.1524)
				(type default)
			)
			(layer "F.SilkS")
		)
		(fp_line
			(start -0.508 -0.9398)
			(end -0.508 0.9398)
			(stroke
				(width 0.1524)
				(type default)
			)
			(layer "F.SilkS")
		)
		(fp_rect
			(start -0.508 0.9398)
			(end 0.508 -0.9398)
			(stroke
				(width 0)
				(type default)
			)
			(fill no)
			(layer "F.CrtYd")
		)
		(fp_rect
			(start -0.508 0.9398)
			(end 0.508 -0.9398)
			(stroke
				(width 0)
				(type default)
			)
			(fill no)
			(layer "F.Fab")
		)
		(pad "1" smd custom
			(at 0 -0.4445 90)
			(size 0.1397 0.1397)
			(layers "F.Cu" "F.Mask" "F.Paste")
			(net "AGND_P1V8_STBY")
			(options
				(clearance outline)
				(anchor circle)
			)
			(primitives
				(gr_poly
					(pts
						(arc
							(start -0.1778 -0.2794)
							(mid -0.249642 -0.249642)
							(end -0.2794 -0.1778)
						)
						(arc
							(start -0.2794 0.1778)
							(mid -0.249642 0.249642)
							(end -0.1778 0.2794)
						)
						(arc
							(start 0.1778 0.2794)
							(mid 0.249642 0.249642)
							(end 0.2794 0.1778)
						)
						(arc
							(start 0.2794 -0.1778)
							(mid 0.249642 -0.249642)
							(end 0.1778 -0.2794)
						)
					)
					(width 0)
					(fill yes)
				)
			)
		)
		(pad "2" smd custom
			(at 0 0.4445 90)
			(size 0.1397 0.1397)
			(layers "F.Cu" "F.Mask" "F.Paste")
			(net "P1V8_STBY_VFB")
			(options
				(clearance outline)
				(anchor circle)
			)
			(primitives
				(gr_poly
					(pts
						(arc
							(start -0.1778 -0.2794)
							(mid -0.249642 -0.249642)
							(end -0.2794 -0.1778)
						)
						(arc
							(start -0.2794 0.1778)
							(mid -0.249642 0.249642)
							(end -0.1778 0.2794)
						)
						(arc
							(start 0.1778 0.2794)
							(mid 0.249642 0.249642)
							(end 0.2794 0.1778)
						)
						(arc
							(start 0.2794 -0.1778)
							(mid 0.249642 -0.249642)
							(end 0.1778 -0.2794)
						)
					)
					(width 0)
					(fill yes)
				)
			)
		)
	)
	(footprint ""
		(layer "F.Cu")
		(at 98.3742 -137.4394 90)
		(property "Reference" "C51"
			(at 0 0 90)
			(layer "F.SilkS")
			(hide yes)
			(effects
				(font
					(size 1.27 1.27)
				)
			)
		)
		(property "Value" "SCD1U16V2KX-3GP"
			(at 1.1811 -2.7051 90)
			(unlocked yes)
			(layer "F.Fab")
			(hide yes)
			(effects
				(font
					(size 1.016 1.016)
					(thickness 0.1524)
				)
			)
		)
		(property "Device Type" "C402H22"
			(at 1.1811 -4.2291 90)
			(unlocked yes)
			(layer "F.Fab")
			(hide yes)
			(effects
				(font
					(size 1.016 1.016)
					(thickness 0.1524)
				)
			)
		)
		(duplicate_pad_numbers_are_jumpers no)
		(fp_rect
			(start -0.4318 0.9525)
			(end 0.4318 -0.9525)
			(stroke
				(width 0)
				(type default)
			)
			(fill no)
			(layer "F.CrtYd")
		)
		(fp_rect
			(start -0.4318 0.9525)
			(end 0.4318 -0.9525)
			(stroke
				(width 0)
				(type default)
			)
			(fill no)
			(layer "F.Fab")
		)
		(pad "1" smd custom
			(at 0 -0.4445 90)
			(size 0.1524 0.1524)
			(layers "F.Cu" "F.Mask" "F.Paste")
			(net "P3V3_STBY")
			(options
				(clearance outline)
				(anchor circle)
			)
			(primitives
				(gr_poly
					(pts
						(arc
							(start 0.3048 -0.2032)
							(mid 0.275042 -0.275042)
							(end 0.2032 -0.3048)
						)
						(arc
							(start -0.2032 -0.3048)
							(mid -0.275042 -0.275042)
							(end -0.3048 -0.2032)
						)
						(arc
							(start -0.3048 0.2032)
							(mid -0.275042 0.275042)
							(end -0.2032 0.3048)
						)
						(arc
							(start 0.2032 0.3048)
							(mid 0.275042 0.275042)
							(end 0.3048 0.2032)
						)
					)
					(width 0)
					(fill yes)
				)
			)
		)
		(pad "2" smd custom
			(at 0 0.4445 90)
			(size 0.1524 0.1524)
			(layers "F.Cu" "F.Mask" "F.Paste")
			(net "GND")
			(options
				(clearance outline)
				(anchor circle)
			)
			(primitives
				(gr_poly
					(pts
						(arc
							(start 0.3048 -0.2032)
							(mid 0.275042 -0.275042)
							(end 0.2032 -0.3048)
						)
						(arc
							(start -0.2032 -0.3048)
							(mid -0.275042 -0.275042)
							(end -0.3048 -0.2032)
						)
						(arc
							(start -0.3048 0.2032)
							(mid -0.275042 0.275042)
							(end -0.2032 0.3048)
						)
						(arc
							(start 0.2032 0.3048)
							(mid 0.275042 0.275042)
							(end 0.3048 0.2032)
						)
					)
					(width 0)
					(fill yes)
				)
			)
		)
	)
	(footprint ""
		(layer "F.Cu")
		(at 84.983828 -85.336634 90)
		(property "Reference" "VIA14"
			(at 0 0 90)
			(layer "F.SilkS")
			(hide yes)
			(effects
				(font
					(size 1.27 1.27)
				)
			)
		)
		(property "Value" "85OHM-8L-1D6MM-L16L18-GP"
			(at 4.064 0.6096 90)
			(unlocked yes)
			(layer "F.Fab")
			(hide yes)
			(effects
				(font
					(size 1.016 1.016)
					(thickness 0.1524)
				)
			)
		)
		(property "Device Type" "VIA-PCIE-4P-368076"
			(at 4.064 -0.9144 90)
			(unlocked yes)
			(layer "F.Fab")
			(hide yes)
			(effects
				(font
					(size 1.016 1.016)
					(thickness 0.1524)
				)
			)
		)
		(duplicate_pad_numbers_are_jumpers no)
		(fp_rect
			(start -1.8415 0.381)
			(end 1.8415 -0.381)
			(stroke
				(width 0)
				(type default)
			)
			(fill no)
			(layer "F.CrtYd")
		)
		(fp_rect
			(start -1.8415 0.381)
			(end 1.8415 -0.381)
			(stroke
				(width 0)
				(type default)
			)
			(fill no)
			(layer "F.Fab")
		)
		(pad "1" thru_hole circle
			(at -1.4605 0 90)
			(size 0.508 0.508)
			(drill 0.254)
			(layers "*.Cu" "*.Mask")
			(remove_unused_layers no)
			(net "GND")
			(clearance 0.127)
			(thermal_gap 0.127)
		)
		(pad "2" thru_hole circle
			(at -0.4445 0 90)
			(size 0.508 0.508)
			(drill 0.254)
			(layers "*.Cu" "*.Mask")
			(remove_unused_layers no)
			(net "PCIE_IOM_TO_COMP_20_DP")
			(clearance 0.127)
			(thermal_gap 0.127)
		)
		(pad "3" thru_hole circle
			(at 0.4445 0 90)
			(size 0.508 0.508)
			(drill 0.254)
			(layers "*.Cu" "*.Mask")
			(remove_unused_layers no)
			(net "PCIE_IOM_TO_COMP_20_DN")
			(clearance 0.127)
			(thermal_gap 0.127)
		)
		(pad "4" thru_hole circle
			(at 1.4605 0 90)
			(size 0.508 0.508)
			(drill 0.254)
			(layers "*.Cu" "*.Mask")
			(remove_unused_layers no)
			(net "GND")
			(clearance 0.127)
			(thermal_gap 0.127)
		)
	)
	(footprint ""
		(layer "F.Cu")
		(at 222.873824 -86.284054)
		(property "Reference" "L31"
			(at 0 0 0)
			(layer "F.SilkS")
			(hide yes)
			(effects
				(font
					(size 1.27 1.27)
				)
			)
		)
		(property "Value" "IND-1UH-191-GP"
			(at -6.7818 -2.1082 0)
			(unlocked yes)
			(layer "F.Fab")
			(hide yes)
			(effects
				(font
					(size 1.016 1.016)
					(thickness 0.1524)
				)
			)
		)
		(property "Device Type" "L109100-2430-UH119"
			(at -6.7818 -3.6322 0)
			(unlocked yes)
			(layer "F.Fab")
			(hide yes)
			(effects
				(font
					(size 1.016 1.016)
					(thickness 0.1524)
				)
			)
		)
		(duplicate_pad_numbers_are_jumpers no)
		(fp_line
			(start -5.2578 -6.4262)
			(end 5.2578 -6.4262)
			(stroke
				(width 0.1524)
				(type default)
			)
			(layer "F.SilkS")
		)
		(fp_line
			(start -5.2578 6.4262)
			(end -5.2578 -6.4262)
			(stroke
				(width 0.1524)
				(type default)
			)
			(layer "F.SilkS")
		)
		(fp_line
			(start 5.2578 -6.4262)
			(end 5.2578 6.4262)
			(stroke
				(width 0.1524)
				(type default)
			)
			(layer "F.SilkS")
		)
		(fp_line
			(start 5.2578 6.4262)
			(end -5.2578 6.4262)
			(stroke
				(width 0.1524)
				(type default)
			)
			(layer "F.SilkS")
		)
		(fp_rect
			(start -5.0038 5.4229)
			(end 5.0038 -5.4229)
			(stroke
				(width 0)
				(type default)
			)
			(fill no)
			(layer "F.CrtYd")
		)
		(fp_poly
			(pts
				(xy -5.5118 6.5024) (xy -5.5118 -6.5024) (xy 5.5118 -6.5024) (xy 5.5118 -0.8509) (xy 5.0038 -0.8509)
				(xy 5.0038 -5.4229) (xy -5.0038 -5.4229) (xy -5.0038 5.4229) (xy 5.0038 5.4229) (xy 5.0038 -0.8382)
				(xy 5.5118 -0.8382) (xy 5.5118 6.5024)
			)
			(stroke
				(width 0)
				(type default)
			)
			(fill no)
			(layer "F.CrtYd")
		)
		(fp_rect
			(start -5.5118 6.5024)
			(end 5.5118 -6.5024)
			(stroke
				(width 0)
				(type default)
			)
			(fill no)
			(layer "F.Fab")
		)
		(pad "1" smd rect
			(at 0 -4.396994)
			(size 3.5052 3.556)
			(layers "F.Cu" "F.Mask" "F.Paste")
			(net "P3V3_M2_LL")
		)
		(pad "2" smd rect
			(at 0 4.396994)
			(size 3.5052 3.556)
			(layers "F.Cu" "F.Mask" "F.Paste")
			(net "P3V3_M2")
		)
	)
)
